FILE_TYPE=LIBRARY_PARTS;
primitive 'TPS3700','TPS3700_SM';
  pin
    'GND':
      PIN_NUMBER='(5)';
      PINUSE='GROUND';
      NO_LOAD_CHECK='Both';
      NO_IO_CHECK='Both';
      NO_ASSERT_CHECK='TRUE';
      NO_DIR_CHECK='TRUE';
      ALLOW_CONNECT='TRUE';
    'INAP':
      PIN_NUMBER='(4)';
      BIDIRECTIONAL='TRUE';
      INPUT_LOAD='(-0.01,0.01)';
      OUTPUT_LOAD='(1.0,-1.0)';
    'INBN':
      PIN_NUMBER='(3)';
      BIDIRECTIONAL='TRUE';
      INPUT_LOAD='(-0.01,0.01)';
      OUTPUT_LOAD='(1.0,-1.0)';
    'OUTA':
      PIN_NUMBER='(6)';
      OUTPUT_LOAD='(1.0,-1.0)';
    'OUTB':
      PIN_NUMBER='(1)';
      OUTPUT_LOAD='(1.0,-1.0)';
    'VDD':
      PIN_NUMBER='(2)';
      PINUSE='POWER';
      NO_LOAD_CHECK='Both';
      NO_IO_CHECK='Both';
      NO_ASSERT_CHECK='TRUE';
      NO_DIR_CHECK='TRUE';
      ALLOW_CONNECT='TRUE';
  end_pin;
  body
    PART_NAME='TPS3700';
    PHYS_DES_PREFIX='U';
  end_body;
end_primitive;

END.
